# BASEBOARD_FAB2 (Tioga Pass) — schematic netlist excerpt (pin names and nets, part order shuffled) for the footprints in the layout excerpt that follows; sources: Cadence DE-HDL packaged netlist, KiCad conversion of Wiwynn_Tioga_Pass_MB.brd

C5D43  CAP_A  22.0UF 4V 20% X6S  pkg 0603V  page 42 : A = PVCCIN_CPU0 ; B = GND
R7C15  RES  0.0 5% CHIP  pkg 0402  page 121 : A = SPI_PCH_MOSI_R ; B = SPI_PCH_MOSI
C8A10  CAP  1000PF 50V 10% EMPTY  pkg 0402LF  page 237 : A = PWRGD_P3V3_STBY ; B = GND

(kicad_pcb
	(version 20260206)
	(generator "pcbnew")
	(generator_version "10.0")
	(general
		(thickness 1.6)
		(legacy_teardrops no)
	)
	(paper "A4")
	(title_block
		(title "Wiwynn_Tioga_Pass_MB.brd")
		(comment 1 "Tioga Pass / footprints 2330-2332 of 4770")
	)
	(layers
		(0 "F.Cu" signal "TOP")
		(4 "In1.Cu" signal "L2GND")
		(6 "In2.Cu" signal "L3")
		(8 "In3.Cu" signal "L4GND")
		(10 "In4.Cu" signal "L5")
		(12 "In5.Cu" signal "L6GND")
		(14 "In6.Cu" signal "L7VCC")
		(16 "In7.Cu" signal "L8VCC")
		(18 "In8.Cu" signal "L9GND")
		(20 "In9.Cu" signal "L10")
		(22 "In10.Cu" signal "L11GND")
		(24 "In11.Cu" signal "L12")
		(26 "In12.Cu" signal "L13GND")
		(2 "B.Cu" signal "BOTTOM")
		(9 "F.Adhes" user "F.Adhesive")
		(11 "B.Adhes" user "B.Adhesive")
		(13 "F.Paste" user "Package Geometry/Pastemask Top")
		(15 "B.Paste" user "Package Geometry/Pastemask Bottom")
		(5 "F.SilkS" user "Ref Des/Silkscreen Top")
		(7 "B.SilkS" user "Ref Des/Silkscreen Bottom")
		(1 "F.Mask" user "Board Geometry/Soldermask Top")
		(3 "B.Mask" user "Board Geometry/Soldermask Bottom")
		(17 "Dwgs.User" user "User.Drawings")
		(19 "Cmts.User" user "User.Comments")
		(21 "Eco1.User" user "User.Eco1")
		(23 "Eco2.User" user "User.Eco2")
		(25 "Edge.Cuts" user "Board Geometry/Outline")
		(27 "Margin" user)
		(31 "F.CrtYd" user "Package Geometry/Place Bound Top")
		(29 "B.CrtYd" user "Package Geometry/Place Bound Bottom")
		(35 "F.Fab" user "Ref Des/Assembly Top")
		(33 "B.Fab" user "Ref Des/Assembly Bottom")
	)
	(footprint ""
		(layer "F.Cu")
		(at 375.158 -88.2015)
		(property "Reference" "R7C15"
			(at 0 0 0)
			(layer "F.SilkS")
			(hide yes)
			(effects
				(font
					(size 1.27 1.27)
				)
			)
		)
		(property "Value" ""
			(at 0 0 0)
			(layer "F.Fab")
			(effects
				(font
					(size 1.27 1.27)
				)
			)
		)
		(duplicate_pad_numbers_are_jumpers no)
		(fp_rect
			(start -0.2794 -0.1016)
			(end 0.2794 0.9906)
			(stroke
				(width 0)
				(type default)
			)
			(fill no)
			(layer "F.CrtYd")
		)
		(fp_line
			(start -0.2794 -0.1016)
			(end -0.2794 0.9906)
			(stroke
				(width 0.1)
				(type default)
			)
			(layer "F.Fab")
		)
		(fp_line
			(start -0.2794 0.9906)
			(end 0.2794 0.9906)
			(stroke
				(width 0.1)
				(type default)
			)
			(layer "F.Fab")
		)
		(fp_line
			(start 0.2794 -0.1016)
			(end -0.2794 -0.1016)
			(stroke
				(width 0.1)
				(type default)
			)
			(layer "F.Fab")
		)
		(fp_line
			(start 0.2794 0.9906)
			(end 0.2794 -0.1016)
			(stroke
				(width 0.1)
				(type default)
			)
			(layer "F.Fab")
		)
		(pad "1" smd rect
			(at 0 0)
			(size 0.508 0.508)
			(layers "F.Cu" "F.Mask" "F.Paste")
			(net "SPI_PCH_MOSI_R")
		)
		(pad "2" smd rect
			(at 0 0.889)
			(size 0.508 0.508)
			(layers "F.Cu" "F.Mask" "F.Paste")
			(net "SPI_PCH_MOSI")
		)
		(zone
			(layer "F.Cu")
			(hatch none 0.5)
			(connect_pads
				(clearance 0)
			)
			(min_thickness 0.25)
			(keepout
				(tracks allowed)
				(vias not_allowed)
				(pads allowed)
				(copperpour not_allowed)
				(footprints allowed)
			)
			(placement
				(enabled no)
				(sheetname "")
			)
			(fill
				(thermal_gap 0.5)
				(thermal_bridge_width 0.5)
				(island_removal_mode 0)
			)
			(polygon
				(pts
					(xy 374.904 -87.9475) (xy 374.904 -87.5665) (xy 375.412 -87.5665) (xy 375.412 -87.9475)
				)
			)
		)
		(zone
			(layer "F.Cu")
			(hatch none 0.5)
			(connect_pads
				(clearance 0)
			)
			(min_thickness 0.25)
			(keepout
				(tracks not_allowed)
				(vias allowed)
				(pads allowed)
				(copperpour not_allowed)
				(footprints allowed)
			)
			(placement
				(enabled no)
				(sheetname "")
			)
			(fill
				(thermal_gap 0.5)
				(thermal_bridge_width 0.5)
				(island_removal_mode 0)
			)
			(polygon
				(pts
					(xy 374.904 -87.9475) (xy 374.904 -87.5665) (xy 375.412 -87.5665) (xy 375.412 -87.9475)
				)
			)
		)
	)
	(footprint ""
		(layer "F.Cu")
		(at 405.283416 -150.468584 90)
		(property "Reference" "C8A10"
			(at 0 0 90)
			(layer "F.SilkS")
			(hide yes)
			(effects
				(font
					(size 1.27 1.27)
				)
			)
		)
		(property "Value" ""
			(at 0 0 90)
			(layer "F.Fab")
			(effects
				(font
					(size 1.27 1.27)
				)
			)
		)
		(duplicate_pad_numbers_are_jumpers no)
		(fp_poly
			(pts
				(xy 0.3048 -0.1016) (xy 0.3048 0.9906) (xy -0.3048 0.9906) (xy -0.3048 -0.1016)
			)
			(stroke
				(width 0)
				(type default)
			)
			(fill no)
			(layer "F.CrtYd")
		)
		(fp_line
			(start 0.3048 -0.1016)
			(end -0.3048 -0.1016)
			(stroke
				(width 0.1)
				(type default)
			)
			(layer "F.Fab")
		)
		(fp_line
			(start -0.3048 -0.1016)
			(end -0.3048 0.9906)
			(stroke
				(width 0.1)
				(type default)
			)
			(layer "F.Fab")
		)
		(fp_line
			(start 0.3048 0.9906)
			(end 0.3048 -0.1016)
			(stroke
				(width 0.1)
				(type default)
			)
			(layer "F.Fab")
		)
		(fp_line
			(start -0.3048 0.9906)
			(end 0.3048 0.9906)
			(stroke
				(width 0.1)
				(type default)
			)
			(layer "F.Fab")
		)
		(pad "1" smd rect
			(at 0 0 90)
			(size 0.508 0.508)
			(layers "F.Cu" "F.Mask" "F.Paste")
			(net "PWRGD_P3V3_STBY")
		)
		(pad "2" smd rect
			(at 0 0.889 90)
			(size 0.508 0.508)
			(layers "F.Cu" "F.Mask" "F.Paste")
			(net "GND")
		)
		(zone
			(layer "F.Cu")
			(hatch none 0.5)
			(connect_pads
				(clearance 0)
			)
			(min_thickness 0.25)
			(keepout
				(tracks allowed)
				(vias not_allowed)
				(pads allowed)
				(copperpour not_allowed)
				(footprints allowed)
			)
			(placement
				(enabled no)
				(sheetname "")
			)
			(fill
				(thermal_gap 0.5)
				(thermal_bridge_width 0.5)
				(island_removal_mode 0)
			)
			(polygon
				(pts
					(xy 405.537416 -150.214584) (xy 405.537416 -150.722584) (xy 405.918416 -150.722584) (xy 405.918416 -150.214584)
				)
			)
		)
		(zone
			(layer "F.Cu")
			(hatch none 0.5)
			(connect_pads
				(clearance 0)
			)
			(min_thickness 0.25)
			(keepout
				(tracks not_allowed)
				(vias allowed)
				(pads allowed)
				(copperpour not_allowed)
				(footprints allowed)
			)
			(placement
				(enabled no)
				(sheetname "")
			)
			(fill
				(thermal_gap 0.5)
				(thermal_bridge_width 0.5)
				(island_removal_mode 0)
			)
			(polygon
				(pts
					(xy 405.918416 -150.214584) (xy 405.918416 -150.722584) (xy 405.537416 -150.722584) (xy 405.537416 -150.214584)
				)
			)
		)
	)
	(footprint ""
		(layer "F.Cu")
		(at 263.186672 -73.318116)
		(property "Reference" "C5D43"
			(at 0 0 0)
			(layer "F.SilkS")
			(hide yes)
			(effects
				(font
					(size 1.27 1.27)
				)
			)
		)
		(property "Value" ""
			(at 0 0 0)
			(layer "F.Fab")
			(effects
				(font
					(size 1.27 1.27)
				)
			)
		)
		(duplicate_pad_numbers_are_jumpers no)
		(fp_poly
			(pts
				(xy -0.4953 -0.2032) (xy 0.4953 -0.2032) (xy 0.4953 1.6002) (xy -0.4953 1.6002)
			)
			(stroke
				(width 0)
				(type default)
			)
			(fill no)
			(layer "F.CrtYd")
		)
		(fp_line
			(start -0.4953 -0.2032)
			(end 0.4953 -0.2032)
			(stroke
				(width 0.1)
				(type default)
			)
			(layer "F.Fab")
		)
		(fp_line
			(start -0.4953 1.6002)
			(end -0.4953 -0.2032)
			(stroke
				(width 0.1)
				(type default)
			)
			(layer "F.Fab")
		)
		(fp_line
			(start 0.4953 -0.2032)
			(end 0.4953 1.6002)
			(stroke
				(width 0.1)
				(type default)
			)
			(layer "F.Fab")
		)
		(fp_line
			(start 0.4953 1.6002)
			(end -0.4953 1.6002)
			(stroke
				(width 0.1)
				(type default)
			)
			(layer "F.Fab")
		)
		(pad "1" smd rect
			(at 0 0)
			(size 0.762 0.889)
			(layers "F.Cu" "F.Mask" "F.Paste")
			(net "PVCCIN_CPU0")
		)
		(pad "2" smd rect
			(at 0 1.397)
			(size 0.762 0.889)
			(layers "F.Cu" "F.Mask" "F.Paste")
			(net "GND")
		)
		(zone
			(layer "F.Cu")
			(hatch none 0.5)
			(connect_pads
				(clearance 0)
			)
			(min_thickness 0.25)
			(keepout
				(tracks not_allowed)
				(vias allowed)
				(pads allowed)
				(copperpour not_allowed)
				(footprints allowed)
			)
			(placement
				(enabled no)
				(sheetname "")
			)
			(fill
				(thermal_gap 0.5)
				(thermal_bridge_width 0.5)
				(island_removal_mode 0)
			)
			(polygon
				(pts
					(xy 262.805672 -72.873616) (xy 263.567672 -72.873616) (xy 263.567672 -72.365616) (xy 262.805672 -72.365616)
				)
			)
		)
	)
)
